# BASEBOARD_FAB2 (Tioga Pass) — schematic parts with pin connectivity, parts 2442–2514 of 4751; source: Cadence DE-HDL packaged netlist (pstxprt.dat, pstxnet.dat, pstchip.dat)

L7F1  INDUCTOR  0.47UH 1% IND  pkg SM  page 231 : 1 = VR_PVPP_ABC_PHASE ; 2 = PVPP_ABC
L7F2  IND-100NH-35-GP  pkg DISCRET-G8  page 217 : 1 = P12V_STBY ; 2 = VR_FET_SW_P12V_STBY_PVDDQ_ABC
L7G1  IND-120NH-30-GP  pkg DISCRET-GB2  page 216 : 1 = VR_PVDDQ_ABC_PH1_SW ; 2 = PVDDQ_ABC
L7G2  IND-120NH-30-GP  pkg DISCRET-GB2  page 216 : 1 = VR_PVDDQ_ABC_PH2_SW ; 2 = PVDDQ_ABC
L8E1  INDUCTOR  2.2UH IND  pkg SM  page 241 : 1 = VR_P5V_STBY_PHASE ; 2 = P5V_STBY
L8F1  IND-1UH-361-GP  pkg DISCRET-GC1  page 240 : 1 = VR_P3V3_STBY_PHASE ; 2 = P3V3_STBY
L25W1  IND-68NH-15-GP  pkg DISCRET-GC1  page 252 : 1 = BMC_VGA_BLUE ; 2 = V_IO_B_J
L25W2  IND-68NH-15-GP  pkg DISCRET-GC1  page 252 : 1 = BMC_VGA_GREEN ; 2 = V_IO_G_J
L25W3  IND-68NH-15-GP  pkg DISCRET-GC1  page 252 : 1 = BMC_VGA_RED ; 2 = V_IO_R_J

L30W1  CHOKE_4PIN  67 OHM EMPTY  pkg SM_B  page 253
  1  \1\  UNSPEC  = USB3_P01_RXP
  2  \2\  UNSPEC  = USB3_P01_FB_RXP
  3  \3\  UNSPEC  = USB3_P01_FB_RXN
  4  \4\  UNSPEC  = USB3_P01_RXN

L30W2  CHOKE_4PIN  67 OHM EMPTY  pkg SM_B  page 253
  1  \1\  UNSPEC  = USB3_P01_C_TXP
  2  \2\  UNSPEC  = USB3_P01_FB_TXP
  3  \3\  UNSPEC  = USB3_P01_FB_TXN
  4  \4\  UNSPEC  = USB3_P01_C_TXN

Q1B1  MOSFET_N  BSZ019N03LS NFET  pkg LCC3  page 198
  1  SRC  UNSPEC  = P12V_FAN
  4  GATE  UNSPEC  = P12V_FAN_SWITCH_G
  5  DRN  UNSPEC  = P12V_STBY

Q1D1  FET_N_DUAL  2N7002DW FET  pkg SMLF  page 199
  1  SOURCE(0)  UNSPEC  = AGND_HSC
  2  GATE(0)  UNSPEC  = A_HSC_LOW_EN
  3  DRAIN(0)  UNSPEC  = A_HSC_ISET_S
  4  SOURCE(0)  UNSPEC  = AGND_HSC
  5  GATE(0)  UNSPEC  = A_HSC_HIGH_EN
  6  DRAIN(0)  UNSPEC  = A_HSC_ISET_S2

Q1D2  FET_N  2N7002 FET  pkg SOT23LF  page 200
  1  GATE  UNSPEC  = FM_OC_DETECT_EN_N
  2  SRC  UNSPEC  = GND
  3  DRN  UNSPEC  = FM_OC_DETECT_EN

Q1D3  NPN  MMBT3904 IC  pkg SM  page 199
  1  B  UNSPEC  = TEMP_SENSOR_B
  2  E  UNSPEC  = TEMP_SENSOR_E
  3  C  UNSPEC  = TEMP_SENSOR_B

Q1E1  2SB2907A-B0-00001-GP  pkg DISCRET-GB1  page 167
  B  B  UNSPEC  = ISENSE_TMP421_2_BC
  C  C  UNSPEC  = ISENSE_TMP421_2_BC
  E  E  UNSPEC  = ISENSE_TMP421_2_E

Q1F1  NPN  MMBT3904 IC  pkg SM  page 89
  1  B  UNSPEC  = FM_ADR_COMPLETE_CPU0_R
  2  E  UNSPEC  = GND
  3  C  UNSPEC  = IRQ_DIMM_SAVE_N

Q1L2  FET_N_DUAL  NTJD4001N FET  pkg SMLF  page 155
  1  SOURCE(0)  UNSPEC  = P5V_STBY_DBG
  2  GATE(0)  UNSPEC  = FM_CPLD_DBG_PWR_EN
  3  DRAIN(0)  UNSPEC  = FM_CPLD_DBG_PWR_EN
  4  SOURCE(0)  UNSPEC  = GND
  5  GATE(0)  UNSPEC  = FM_CPLD_DBG_PWR_EN_R_N
  6  DRAIN(0)  UNSPEC  = P5V_STBY

Q1L3  NPN  MMBT3904 IC  pkg SM  page 168
  1  B  UNSPEC  = FM_DB_UART_SEL4_N
  2  E  UNSPEC  = GND
  3  C  UNSPEC  = FM_DB_PRESENT

Q1L4  FET_N_DUAL  2N7002DW FET  pkg SMLF  page 168
  1  SOURCE(0)  UNSPEC  = GND
  2  GATE(0)  UNSPEC  = FM_DB_PRESENT
  3  DRAIN(0)  UNSPEC  = TP_FET_Q56_3
  4  SOURCE(0)  UNSPEC  = TP_FET_Q56_4
  5  GATE(0)  UNSPEC  = TP_FET_Q56_4
  6  DRAIN(0)  UNSPEC  = FM_POST_CARD_PRES_BMC_N

Q1P2  FET_N  2N7002 FET  pkg SOT23LF  page 196
  1  GATE  UNSPEC  = PWRGD_P5V_N
  2  SRC  UNSPEC  = GND
  3  DRN  UNSPEC  = PWRGD_P5V_R

Q1W1  FET_N  2N7002 FET  pkg SOT23LF  page 250
  1  GATE  UNSPEC  = FM_OCP_MEZZA_PRES_N
  2  SRC  UNSPEC  = GND
  3  DRN  UNSPEC  = FM_OCP_MEZZA_PRES

Q1W2  FET_N_DUAL  2N7002DW FET  pkg SMLF  page 250
  1  SOURCE(0)  UNSPEC  = GND
  2  GATE(0)  UNSPEC  = FM_OCP_MEZZB_PRES_N
  3  DRAIN(0)  UNSPEC  = FM_OCP_MEZZB_PRES_1V05_PCH_N
  4  SOURCE(0)  UNSPEC  = GND
  5  GATE(0)  UNSPEC  = FM_OCP_MEZZB_PRES_LVT3_BMC
  6  DRAIN(0)  UNSPEC  = FM_OCP_MEZZB_PRES_LVT3_BMC

Q1W4  FET_N_DUAL  2N7002DW FET  pkg SMLF  page 250
  1  SOURCE(0)  UNSPEC  = GND
  2  GATE(0)  UNSPEC  = FM_OCP_MEZZC_PRES_N
  3  DRAIN(0)  UNSPEC  = FM_OCP_MEZZC_PRES_1V05_PCH_N
  4  SOURCE(0)  UNSPEC  = GND
  5  GATE(0)  UNSPEC  = FM_OCP_MEZZC_PRES_LVT3_BMC
  6  DRAIN(0)  UNSPEC  = FM_OCP_MEZZC_PRES_LVT3_BMC

Q1W5  FET_N  2N7002 FET  pkg SOT23LF  page 199
  1  GATE  UNSPEC  = A_HSC_HIGH_EN
  2  SRC  UNSPEC  = GND
  3  DRN  UNSPEC  = A_HSC_LOW_GATE

Q1W6  NPN  MMBT3904 IC  pkg SM  page 89
  1  B  UNSPEC  = FM_ADR_COMPLETE_CPU1_R
  2  E  UNSPEC  = GND
  3  C  UNSPEC  = FM_ADR_COMPLETE_CPU1_N

Q2P1  FET_N  2N7002 FET  pkg SOT23LF  page 170
  1  GATE  UNSPEC  = FM_PMBUS_ALERT_BUF_EN_N
  2  SRC  UNSPEC  = GND
  3  DRN  UNSPEC  = FM_PMBUS_ALERT_BUF_EN

Q2T1  NPN  MMBT3904 IC  pkg SM  page 157
  1  B  UNSPEC  = H_CPU0_FAST_WAKE_B_N
  2  E  UNSPEC  = GND
  3  C  UNSPEC  = H_CPU0_FAST_WAKE

Q2T2  FET_N  2N7002 FET  pkg SOT23LF  page 157
  1  GATE  UNSPEC  = H_CPU0_FAST_WAKE
  2  SRC  UNSPEC  = GND
  3  DRN  UNSPEC  = H_CPU0_FAST_WAKE_LVT3_N

Q2U1  FET_N_DUAL  NTJD4001N FET  pkg SMLF  page 95
  1  SOURCE(0)  UNSPEC  = GND
  2  GATE(0)  UNSPEC  = FM_SYS_THROTTLE_LVC3
  3  DRAIN(0)  UNSPEC  = H_CPU0_MEMDEF_MEMHOT_G_N
  4  SOURCE(0)  UNSPEC  = GND
  5  GATE(0)  UNSPEC  = FM_SYS_THROTTLE_LVC3
  6  DRAIN(0)  UNSPEC  = H_CPU0_MEMABC_MEMHOT_G_N

Q3U1  FET_N_DUAL  NTJD4001N FET  pkg SMLF  page 94
  1  SOURCE(0)  UNSPEC  = GND
  2  GATE(0)  UNSPEC  = IRQ_PVDDQ_ABC_VRHOT_LVT3_N
  3  DRAIN(0)  UNSPEC  = H_CPU0_MEMABC_MEMHOT_G_N
  4  SOURCE(0)  UNSPEC  = GND
  5  GATE(0)  UNSPEC  = H_CPU0_MEMABC_MEMHOT
  6  DRAIN(0)  UNSPEC  = H_CPU0_MEMABC_MEMHOT

Q4B1  FET_N_DUAL  NTJD4001N FET  pkg SMLF  page 94
  1  SOURCE(0)  UNSPEC  = GND
  2  GATE(0)  UNSPEC  = IRQ_PVDDQ_KLM_VRHOT_LVT3_N
  3  DRAIN(0)  UNSPEC  = H_CPU1_MEMKLM_MEMHOT_G_N
  4  SOURCE(0)  UNSPEC  = GND
  5  GATE(0)  UNSPEC  = H_CPU1_MEMKLM_MEMHOT
  6  DRAIN(0)  UNSPEC  = H_CPU1_MEMKLM_MEMHOT

Q4B2  FET_N_DUAL  NTJD4001N FET  pkg SMLF  page 95
  1  SOURCE(0)  UNSPEC  = GND
  2  GATE(0)  UNSPEC  = FM_SYS_THROTTLE_LVC3
  3  DRAIN(0)  UNSPEC  = H_CPU1_MEMKLM_MEMHOT_G_N
  4  SOURCE(0)  UNSPEC  = GND
  5  GATE(0)  UNSPEC  = FM_SYS_THROTTLE_LVC3
  6  DRAIN(0)  UNSPEC  = H_CPU1_MEMGHJ_MEMHOT_G_N

Q4U1  FET_N_DUAL  NTJD4001N FET  pkg SMLF  page 94
  1  SOURCE(0)  UNSPEC  = GND
  2  GATE(0)  UNSPEC  = FM_DIMM_EVENT_COD_N
  3  DRAIN(0)  UNSPEC  = FM_MEM_THERM_EVENT_LVT3_N
  4  SOURCE(0)  UNSPEC  = GND
  5  GATE(0)  UNSPEC  = FM_DIMM_EVENT_FET
  6  DRAIN(0)  UNSPEC  = FM_DIMM_EVENT_FET

Q4W1  FET_N_DUAL  2N7002DW FET  pkg SMLF  page 102
  1  SOURCE(0)  UNSPEC  = SMB_HOST_STBY_LVC3_SDA_R2
  2  GATE(0)  UNSPEC  = P3V3_DB1200_R1
  3  DRAIN(0)  UNSPEC  = SMB_HOST_STBY_LVC3_SCL
  4  SOURCE(0)  UNSPEC  = SMB_HOST_STBY_LVC3_SCL_R2
  5  GATE(0)  UNSPEC  = P3V3_DB1200_R1
  6  DRAIN(0)  UNSPEC  = SMB_HOST_STBY_LVC3_SDA

Q4W2  FET_N  2N7002 FET  pkg SOT23LF  page 102
  1  GATE  UNSPEC  = FM_DB1200_PWRGD
  2  SRC  UNSPEC  = GND
  3  DRN  UNSPEC  = FM_DB1200_PWRGD_R

Q6W1  FET_N  2N7002 FET  pkg SOT23LF  page 200
  1  GATE  UNSPEC  = UV_HIGH_SET
  2  SRC  UNSPEC  = GND
  3  DRN  UNSPEC  = UV_HIGH_SET_N

Q6W2  NPN  MMBT3904 IC  pkg SM  page 168
  1  B  UNSPEC  = FM_UART_SEL_N
  2  E  UNSPEC  = GND
  3  C  UNSPEC  = FM_SOL_UART_CH_SEL

Q6W4  FET_N  2N7002 FET  pkg SOT23LF  page 168
  1  GATE  UNSPEC  = DEBUG_CARD2_PRSNT
  2  SRC  UNSPEC  = GND
  3  DRN  UNSPEC  = FM_POST_CARD_PRES_BMC_N

Q7D1  FET_N  2N7002 FET  pkg SOT23LF  page 134
  1  GATE  UNSPEC  = FM_THERMTRIP_DLY_R
  2  SRC  UNSPEC  = GND
  3  DRN  UNSPEC  = FM_PCH_LVC1_THERMTRIP_N

Q7E1  FET_N_DUAL  NTJD4001N FET  pkg SMLF  page 94
  1  SOURCE(0)  UNSPEC  = GND
  2  GATE(0)  UNSPEC  = IRQ_PVDDQ_DEF_VRHOT_LVT3_N
  3  DRAIN(0)  UNSPEC  = H_CPU0_MEMDEF_MEMHOT_G_N
  4  SOURCE(0)  UNSPEC  = GND
  5  GATE(0)  UNSPEC  = H_CPU0_MEMDEF_MEMHOT
  6  DRAIN(0)  UNSPEC  = H_CPU0_MEMDEF_MEMHOT

Q7E2  FET_N_DUAL  NTJD4001N FET  pkg SMLF  page 94
  1  SOURCE(0)  UNSPEC  = GND
  2  GATE(0)  UNSPEC  = IRQ_PVDDQ_GHJ_VRHOT_LVT3_N
  3  DRAIN(0)  UNSPEC  = H_CPU1_MEMGHJ_MEMHOT_G_N
  4  SOURCE(0)  UNSPEC  = GND
  5  GATE(0)  UNSPEC  = H_CPU1_MEMGHJ_MEMHOT
  6  DRAIN(0)  UNSPEC  = H_CPU1_MEMGHJ_MEMHOT

Q7E3  FET_N_DUAL  NTJD4001N FET  pkg SMLF  page 95
  1  SOURCE(0)  UNSPEC  = GND
  2  GATE(0)  UNSPEC  = FM_SYS_THROTTLE_LVC3
  3  DRAIN(0)  UNSPEC  = H_CPU1_PROCHOT_G_N
  4  SOURCE(0)  UNSPEC  = GND
  5  GATE(0)  UNSPEC  = FM_SYS_THROTTLE_LVC3
  6  DRAIN(0)  UNSPEC  = H_CPU0_PROCHOT_G_N

Q7E4  FET_N  2N7002 FET  pkg SOT23LF  page 95
  1  GATE  UNSPEC  = FM_THROTTLE_R_N
  2  SRC  UNSPEC  = GND
  3  DRN  UNSPEC  = FM_SYS_THROTTLE_LVC3

Q7E5  FET_N_DUAL  NTJD4001N FET  pkg SMLF  page 95
  1  SOURCE(0)  UNSPEC  = GND
  2  GATE(0)  UNSPEC  = IRQ_CPU0_PROCHOT_G_N
  3  DRAIN(0)  UNSPEC  = H_CPU0_PROCHOT_G_N
  4  SOURCE(0)  UNSPEC  = GND
  5  GATE(0)  UNSPEC  = IRQ_CPU0_VRHOT
  6  DRAIN(0)  UNSPEC  = IRQ_CPU0_VRHOT

Q7E6  FET_N_DUAL  NTJD4001N FET  pkg SMLF  page 95
  1  SOURCE(0)  UNSPEC  = GND
  2  GATE(0)  UNSPEC  = IRQ_CPU1_PROCHOT_G_N
  3  DRAIN(0)  UNSPEC  = H_CPU1_PROCHOT_G_N
  4  SOURCE(0)  UNSPEC  = GND
  5  GATE(0)  UNSPEC  = IRQ_CPU1_VRHOT
  6  DRAIN(0)  UNSPEC  = IRQ_CPU1_VRHOT

Q7E7  MOSFET_N  BSZ019N03LS NFET  pkg LCC3  page 198
  1  SRC  UNSPEC  = P12V
  4  GATE  UNSPEC  = P12V_SWITCH_G
  5  DRN  UNSPEC  = P12V_STBY

Q7E8  FET_N  2N7002 FET  pkg SOT23LF  page 95
  1  GATE  UNSPEC  = FM_SYS_THROTTLE_LVC3
  2  SRC  UNSPEC  = GND
  3  DRN  UNSPEC  = FM_PWRBRK_N

Q8B1  MOSFET_N  BSZ019N03LS NFET  pkg LCC3  page 198
  1  SRC  UNSPEC  = P5V
  4  GATE  UNSPEC  = P5V_SWITCH_G
  5  DRN  UNSPEC  = P5V_STBY

Q8D1  NPN_DUAL  MBT3904 XSTR  pkg SSOPLF  page 89
  1  E(0)  UNSPEC  = GND
  2  B(0)  UNSPEC  = IRQ_DIMM_SAVE_LVT3
  3  C(0)  UNSPEC  = IRQ_DIMM_SAVE_LVT3
  4  E(0)  UNSPEC  = GND
  5  B(0)  UNSPEC  = IRQ_DIMM_SAVE_R_N
  6  C(0)  UNSPEC  = IRQ_DIMM_SAVE_LVT3_N

Q8D2  FET_N  2N7002 FET  pkg SOT23LF  page 134
  1  GATE  UNSPEC  = RST_PLTRST_BUF_N
  2  SRC  UNSPEC  = FM_PCH_BMC_THERMTRIP_EXI_STRAP_
  3  DRN  UNSPEC  = FM_PCH_BMC_THERMTRIP_N

Q8E1  FET_N  2N7002 FET  pkg SOT23LF  page 136
  1  GATE  UNSPEC  = RST_PLTRST_N
  2  SRC  UNSPEC  = GND
  3  DRN  UNSPEC  = RST_PLTRST_TOP_SWAP

Q8E2  FET_N  2N7002 FET  pkg SOT23LF  page 126
  1  GATE  UNSPEC  = RST_RSMRST_DLY
  2  SRC  UNSPEC  = GND
  3  DRN  UNSPEC  = IRQ_SML0_ALERT_N

Q8F1  FET_N  2N7002 FET  pkg SOT23LF  page 154
  1  GATE  UNSPEC  = FM_BACKUP_BIOS_SEL_N
  2  SRC  UNSPEC  = GND
  3  DRN  UNSPEC  = FM_DUAL_BIOS_SEL_N

Q8F2  FET_N  2N7002 FET  pkg SOT23LF  page 170
  1  GATE  UNSPEC  = FM_FAST_PROCHOT_EN_N
  2  SRC  UNSPEC  = GND
  3  DRN  UNSPEC  = FM_FAST_PROCHOT_EN

Q8G1  MOSFET_N  BSZ019N03LS NFET  pkg LCC3  page 198
  1  SRC  UNSPEC  = P3V3
  4  GATE  UNSPEC  = P3V3_SWITCH_G
  5  DRN  UNSPEC  = P3V3_STBY

Q8W1  NPN_DUAL  MBT3904 XSTR  pkg SSOPLF  page 89
  1  E(0)  UNSPEC  = GND
  2  B(0)  UNSPEC  = IRQ_DIMM_SAVE_LVT3_CPU1
  3  C(0)  UNSPEC  = IRQ_DIMM_SAVE_LVT3_CPU1
  4  E(0)  UNSPEC  = GND
  5  B(0)  UNSPEC  = IRQ_DIMM_SAVE_CPU1_R_N
  6  C(0)  UNSPEC  = IRQ_DIMM_SAVE_LVT3_N

Q9A1  NPN_DUAL  MBT3904 EMPTY  pkg SSOPLF  page 111
  1  E(0)  UNSPEC  = XDP_CPU_GTL_TCK_R2
  2  B(0)  UNSPEC  = XDP_CPU_TCK_BUF
  3  C(0)  UNSPEC  = P3V3
  4  E(0)  UNSPEC  = XDP_CPU_TCK0
  5  B(0)  UNSPEC  = XDP_CPU_TCK_BUF
  6  C(0)  UNSPEC  = XDP_CPU_TCK_BUF

Q9A2  FET_N_DUAL  NTJD4001N FET  pkg SMLF  page 119
  1  SOURCE(0)  UNSPEC  = GND
  2  GATE(0)  UNSPEC  = FM_PWR_LED_N
  3  DRAIN(0)  UNSPEC  = FM_PWR_LED_K
  4  SOURCE(0)  UNSPEC  = GND
  5  GATE(0)  UNSPEC  = FM_PWR_LED
  6  DRAIN(0)  UNSPEC  = FM_PWR_LED

Q9A3  FET_N  2N7002 FET  pkg SOT23LF  page 175
  1  GATE  UNSPEC  = FM_BIOS_TOP_SWAP_SPKR
  2  SRC  UNSPEC  = GND
  3  DRN  UNSPEC  = FM_SPEAKER_PCH_N

Q9B1  2SB2907A-B0-00001-GP  pkg DISCRET-GB1  page 167
  B  B  UNSPEC  = ISENSE_TMP421_1_BC
  C  C  UNSPEC  = ISENSE_TMP421_1_BC
  E  E  UNSPEC  = ISENSE_TMP421_1_E

Q9E1  FET_N_DUAL  NTJD4001N FET  pkg SMLF  page 151
  1  SOURCE(0)  UNSPEC  = GND
  2  GATE(0)  UNSPEC  = FM_BMC_HEARTBEAT_N
  3  DRAIN(0)  UNSPEC  = FM_HEARTBEAT_LED_K
  4  SOURCE(0)  UNSPEC  = GND
  5  GATE(0)  UNSPEC  = FM_HEARTBEAT_LED
  6  DRAIN(0)  UNSPEC  = FM_HEARTBEAT_LED

Q9F1  FET_N_DUAL  NTJD4001N FET  pkg SMLF  page 177
  1  SOURCE(0)  UNSPEC  = GND
  2  GATE(0)  UNSPEC  = FM_BMC_FAULT_LED_N
  3  DRAIN(0)  UNSPEC  = FM_RED_LED_CATHODE
  4  SOURCE(0)  UNSPEC  = GND
  5  GATE(0)  UNSPEC  = FM_BMC_FAULT_LED
  6  DRAIN(0)  UNSPEC  = FM_BMC_FAULT_LED

Q9G1  FET_N_DUAL  NTJD4001N FET  pkg SMLF  page 169
  1  SOURCE(0)  UNSPEC  = GND
  2  GATE(0)  UNSPEC  = FM_BATTERY_SENSE_EN_N
  3  DRAIN(0)  UNSPEC  = P3V_BAT_SOURCE_R
  4  SOURCE(0)  UNSPEC  = A_P3V_BAT_SCALED
  5  GATE(0)  UNSPEC  = FM_BATTERY_SENSE_EN
  6  DRAIN(0)  UNSPEC  = FM_BATTERY_SENSE_EN

Q9P1  FET_N_DUAL  2N7002DW FET  pkg SMLF  page 200
  1  SOURCE(0)  UNSPEC  = GND
  2  GATE(0)  UNSPEC  = A_HSC_LOW_GATE
  3  DRAIN(0)  UNSPEC  = IRQ_UV_DETECT_N
  4  SOURCE(0)  UNSPEC  = GND
  5  GATE(0)  UNSPEC  = A_P12V_STBY_FPH_GATE
  6  DRAIN(0)  UNSPEC  = A_HSC_LOW_DRAIN

Q9T1  NPN  MMBT3904 IC  pkg SM  page 181
  1  B  UNSPEC  = FM_MATED_IN_D2_N
  2  E  UNSPEC  = GND
  3  C  UNSPEC  = FM_P12V_HOTSWAP0_EN

Q9W1  FET_N  2N7002 FET  pkg SOT23LF  page 249
  1  GATE  UNSPEC  = BMC_TPM_HW_C_RST
  2  SRC  UNSPEC  = GND
  3  DRN  UNSPEC  = FM_TPM_PRES_RST_N

Q9W2  NPN  MMBT3904 IC  pkg SM  page 249
  1  B  UNSPEC  = FM_TPM_PRES_RST_N_R
  2  E  UNSPEC  = GND
  3  C  UNSPEC  = FM_TPM_PRES_RST

Q9W3  NPN  MMBT3904 IC  pkg SM  page 249
  1  B  UNSPEC  = FM_TPM_PRES_RST
  2  E  UNSPEC  = GND
  3  C  UNSPEC  = RST_BMC_EXTRST_N

Q9W4  LMV331IDCKRG4-GP  pkg DISCRET-G  page 249
  1  \+in\  IN  = FM_TPM_PRES_RST_N
  2  GND  POWER  = GND
  3  \-in\  IN  = VREF_2V2
  4  \out\  OUT  = FM_TPM_PRES_N
  5  VCC  POWER  = P5V_STBY

Q12W1  BSL308C-H6327-GP  pkg DISCRET-GB1  page 197
  1  \gate#1\  UNSPEC  = PWRGD_PVDDQ_ABC
  2  \source#2\  UNSPEC  = P12V_NVDIMM_ABC
  3  \gate#3\  UNSPEC  = PWRGD_PVDDQ_ABC_N
  4  \drain#4\  UNSPEC  = P12V_NVDIMM_ABC_D
  5  \source#5\  UNSPEC  = GND
  6  \drain#6\  UNSPEC  = PWRGD_PVDDQ_ABC_N

Q12W2  BSL308C-H6327-GP  pkg DISCRET-GB1  page 197
  1  \gate#1\  UNSPEC  = PWRGD_PVDDQ_DEF
  2  \source#2\  UNSPEC  = P12V_NVDIMM_DEF
  3  \gate#3\  UNSPEC  = PWRGD_PVDDQ_DEF_N
  4  \drain#4\  UNSPEC  = P12V_NVDIMM_DEF_D
  5  \source#5\  UNSPEC  = GND
  6  \drain#6\  UNSPEC  = PWRGD_PVDDQ_DEF_N

Q12W3  BSL308C-H6327-GP  pkg DISCRET-GB1  page 197
  1  \gate#1\  UNSPEC  = PWRGD_PVDDQ_GHJ
  2  \source#2\  UNSPEC  = P12V_NVDIMM_GHJ
  3  \gate#3\  UNSPEC  = PWRGD_PVDDQ_GHJ_N
  4  \drain#4\  UNSPEC  = P12V_NVDIMM_GHJ_D
  5  \source#5\  UNSPEC  = GND
  6  \drain#6\  UNSPEC  = PWRGD_PVDDQ_GHJ_N
